# SCM (Grand Teton) — schematic netlist excerpt (pin names and nets, part order shuffled) for the footprints in the layout excerpt that follows; sources: Cadence DE-HDL packaged netlist, KiCad conversion of 12092022_DA0F0TMDCD0_F0T_Management_Board_D_brd_V3_OCP.brd

R726  Q_RES  0 5% CHIP  pkg 0402LF  page 30 : A = SPA_SIN_SW_BUF_R ; B = SPA_SIN_SW_BUF
C23  Q_CAP  0.1UF 25V 10% X7R  pkg 0402  page 12 : A = P0V6_DDR_VREF_AUX ; B = GND

(kicad_pcb
	(version 20260206)
	(generator "pcbnew")
	(generator_version "10.0")
	(general
		(thickness 1.6)
		(legacy_teardrops no)
	)
	(paper "A4")
	(title_block
		(title "12092022_DA0F0TMDCD0_F0T_Management_Board_D_brd_V3_OCP.brd")
		(comment 1 "Grand Teton / footprints 1314-1315 of 1440")
	)
	(layers
		(0 "F.Cu" signal "TOP")
		(4 "In1.Cu" signal "GND")
		(6 "In2.Cu" signal "IN1")
		(8 "In3.Cu" signal "GND1")
		(10 "In4.Cu" signal "IN2")
		(12 "In5.Cu" signal "VCC")
		(14 "In6.Cu" signal "VCC1")
		(16 "In7.Cu" signal "IN3")
		(18 "In8.Cu" signal "GND2")
		(20 "In9.Cu" signal "IN4")
		(22 "In10.Cu" signal "GND3")
		(2 "B.Cu" signal "BOTTOM")
		(9 "F.Adhes" user "F.Adhesive")
		(11 "B.Adhes" user "B.Adhesive")
		(13 "F.Paste" user "Package Geometry/Pastemask Top")
		(15 "B.Paste" user "Package Geometry/Pastemask Bottom")
		(5 "F.SilkS" user "Ref Des/Silkscreen Top")
		(7 "B.SilkS" user "Ref Des/Silkscreen Bottom")
		(1 "F.Mask" user "Board Geometry/Soldermask Top")
		(3 "B.Mask" user "Board Geometry/Soldermask Bottom")
		(17 "Dwgs.User" user "User.Drawings")
		(19 "Cmts.User" user "User.Comments")
		(21 "Eco1.User" user "User.Eco1")
		(23 "Eco2.User" user "User.Eco2")
		(25 "Edge.Cuts" user "Board Geometry/Outline")
		(27 "Margin" user)
		(31 "F.CrtYd" user "Package Geometry/Place Bound Top")
		(29 "B.CrtYd" user "Package Geometry/Place Bound Bottom")
		(35 "F.Fab" user "Ref Des/Assembly Top")
		(33 "B.Fab" user "Ref Des/Assembly Bottom")
	)
	(footprint ""
		(layer "B.Cu")
		(at 20.4724 -65.1256 90)
		(property "Reference" "R726"
			(at 0 0 90)
			(layer "B.SilkS")
			(hide yes)
			(effects
				(font
					(size 1.27 1.27)
				)
				(justify mirror)
			)
		)
		(property "Value" ""
			(at 0 0 90)
			(layer "B.Fab")
			(effects
				(font
					(size 1.27 1.27)
				)
				(justify mirror)
			)
		)
		(duplicate_pad_numbers_are_jumpers no)
		(fp_line
			(start 0.7874 -0.4064)
			(end -0.7874 -0.4064)
			(stroke
				(width 0.1524)
				(type default)
			)
			(layer "B.SilkS")
		)
		(fp_line
			(start -0.7874 -0.4064)
			(end -0.7874 0.4064)
			(stroke
				(width 0.1524)
				(type default)
			)
			(layer "B.SilkS")
		)
		(fp_line
			(start 0.7874 0.4064)
			(end 0.7874 -0.4064)
			(stroke
				(width 0.1524)
				(type default)
			)
			(layer "B.SilkS")
		)
		(fp_line
			(start -0.7874 0.4064)
			(end 0.7874 0.4064)
			(stroke
				(width 0.1524)
				(type default)
			)
			(layer "B.SilkS")
		)
		(fp_line
			(start 0.67945 -0.305054)
			(end 0.12065 -0.305054)
			(stroke
				(width 0.1)
				(type default)
			)
			(layer "B.Fab")
		)
		(fp_line
			(start 0.12065 -0.305054)
			(end 0.12065 -0.2794)
			(stroke
				(width 0.1)
				(type default)
			)
			(layer "B.Fab")
		)
		(fp_line
			(start -0.12065 -0.3048)
			(end -0.67945 -0.3048)
			(stroke
				(width 0.1)
				(type default)
			)
			(layer "B.Fab")
		)
		(fp_line
			(start -0.67945 -0.3048)
			(end -0.67945 0.3048)
			(stroke
				(width 0.1)
				(type default)
			)
			(layer "B.Fab")
		)
		(fp_line
			(start 0.12065 -0.2794)
			(end -0.12065 -0.2794)
			(stroke
				(width 0.1)
				(type default)
			)
			(layer "B.Fab")
		)
		(fp_line
			(start -0.12065 -0.2794)
			(end -0.12065 -0.3048)
			(stroke
				(width 0.1)
				(type default)
			)
			(layer "B.Fab")
		)
		(fp_line
			(start 0.12065 0.2794)
			(end 0.12065 0.3048)
			(stroke
				(width 0.1)
				(type default)
			)
			(layer "B.Fab")
		)
		(fp_line
			(start -0.120396 0.2794)
			(end 0.12065 0.2794)
			(stroke
				(width 0.1)
				(type default)
			)
			(layer "B.Fab")
		)
		(fp_line
			(start 0.67945 0.3048)
			(end 0.67945 -0.305054)
			(stroke
				(width 0.1)
				(type default)
			)
			(layer "B.Fab")
		)
		(fp_line
			(start 0.12065 0.3048)
			(end 0.67945 0.3048)
			(stroke
				(width 0.1)
				(type default)
			)
			(layer "B.Fab")
		)
		(fp_line
			(start -0.120396 0.3048)
			(end -0.120396 0.2794)
			(stroke
				(width 0.1)
				(type default)
			)
			(layer "B.Fab")
		)
		(fp_line
			(start -0.67945 0.3048)
			(end -0.120396 0.3048)
			(stroke
				(width 0.1)
				(type default)
			)
			(layer "B.Fab")
		)
		(pad "1" smd circle
			(at 0.40005 0 270)
			(size 0 0)
			(layers "B.Cu" "B.Mask" "B.Paste")
			(net "SPA_SIN_SW_BUF_R")
		)
		(pad "2" smd circle
			(at -0.40005 0 270)
			(size 0 0)
			(layers "B.Cu" "B.Mask" "B.Paste")
			(net "SPA_SIN_SW_BUF")
		)
	)
	(footprint ""
		(layer "B.Cu")
		(at 60.663328 -52.136294)
		(property "Reference" "C23"
			(at 0 0 0)
			(layer "B.SilkS")
			(hide yes)
			(effects
				(font
					(size 1.27 1.27)
				)
				(justify mirror)
			)
		)
		(property "Value" ""
			(at 0 0 0)
			(layer "B.Fab")
			(effects
				(font
					(size 1.27 1.27)
				)
				(justify mirror)
			)
		)
		(duplicate_pad_numbers_are_jumpers no)
		(fp_line
			(start -0.7874 -0.4064)
			(end -0.7874 0.4064)
			(stroke
				(width 0.1524)
				(type default)
			)
			(layer "B.SilkS")
		)
		(fp_line
			(start -0.7874 0.4064)
			(end 0.7874 0.4064)
			(stroke
				(width 0.1524)
				(type default)
			)
			(layer "B.SilkS")
		)
		(fp_line
			(start 0.7874 -0.4064)
			(end -0.7874 -0.4064)
			(stroke
				(width 0.1524)
				(type default)
			)
			(layer "B.SilkS")
		)
		(fp_line
			(start 0.7874 0.4064)
			(end 0.7874 -0.4064)
			(stroke
				(width 0.1524)
				(type default)
			)
			(layer "B.SilkS")
		)
		(fp_line
			(start -0.67945 -0.3048)
			(end -0.67945 0.3048)
			(stroke
				(width 0.1)
				(type default)
			)
			(layer "B.Fab")
		)
		(fp_line
			(start -0.67945 0.3048)
			(end -0.120396 0.3048)
			(stroke
				(width 0.1)
				(type default)
			)
			(layer "B.Fab")
		)
		(fp_line
			(start -0.12065 -0.3048)
			(end -0.67945 -0.3048)
			(stroke
				(width 0.1)
				(type default)
			)
			(layer "B.Fab")
		)
		(fp_line
			(start -0.12065 -0.2794)
			(end -0.12065 -0.3048)
			(stroke
				(width 0.1)
				(type default)
			)
			(layer "B.Fab")
		)
		(fp_line
			(start -0.120396 0.2794)
			(end 0.12065 0.2794)
			(stroke
				(width 0.1)
				(type default)
			)
			(layer "B.Fab")
		)
		(fp_line
			(start -0.120396 0.3048)
			(end -0.120396 0.2794)
			(stroke
				(width 0.1)
				(type default)
			)
			(layer "B.Fab")
		)
		(fp_line
			(start 0.12065 -0.305054)
			(end 0.12065 -0.2794)
			(stroke
				(width 0.1)
				(type default)
			)
			(layer "B.Fab")
		)
		(fp_line
			(start 0.12065 -0.2794)
			(end -0.12065 -0.2794)
			(stroke
				(width 0.1)
				(type default)
			)
			(layer "B.Fab")
		)
		(fp_line
			(start 0.12065 0.2794)
			(end 0.12065 0.3048)
			(stroke
				(width 0.1)
				(type default)
			)
			(layer "B.Fab")
		)
		(fp_line
			(start 0.12065 0.3048)
			(end 0.67945 0.3048)
			(stroke
				(width 0.1)
				(type default)
			)
			(layer "B.Fab")
		)
		(fp_line
			(start 0.67945 -0.305054)
			(end 0.12065 -0.305054)
			(stroke
				(width 0.1)
				(type default)
			)
			(layer "B.Fab")
		)
		(fp_line
			(start 0.67945 0.3048)
			(end 0.67945 -0.305054)
			(stroke
				(width 0.1)
				(type default)
			)
			(layer "B.Fab")
		)
		(pad "1" smd circle
			(at 0.40005 0 180)
			(size 0 0)
			(layers "B.Cu" "B.Mask" "B.Paste")
			(net "P0V6_DDR_VREF_AUX")
		)
		(pad "2" smd circle
			(at -0.40005 0 180)
			(size 0 0)
			(layers "B.Cu" "B.Mask" "B.Paste")
			(net "GND")
		)
	)
)
